# BASEBOARD_FAB2 (Tioga Pass) — schematic netlist excerpt (pin names and nets, part order shuffled) for the footprints in the layout excerpt that follows; sources: Cadence DE-HDL packaged netlist, KiCad conversion of Wiwynn_Tioga_Pass_MB.brd

J8E3  SCONN80_E67482007  CONN  pkg SM  page 187
  IO1  = FM_MEZZB_PRSNT1_N
  IO2  = P12V_STBY
  IO3  = GND
  IO4  = P12V_STBY
  IO5  = P3E_CPU0_PE3_OCP_RXP<7>
  IO6  = TP_RSVD_B1
  IO7  = P3E_CPU0_PE3_OCP_RXN<7>
  IO8  = GND
  IO9  = GND
  IO10  = P3E_OCP_CPU0_PE3_C_TXP<7>
  IO11  = GND
  IO12  = P3E_OCP_CPU0_PE3_C_TXN<7>
  IO13  = P3E_CPU0_PE3_OCP_RXN<6>
  IO14  = GND
  IO15  = P3E_CPU0_PE3_OCP_RXP<6>
  IO16  = GND
  IO17  = GND
  IO18  = P3E_OCP_CPU0_PE3_C_TXP<6>
  IO19  = GND
  IO20  = P3E_OCP_CPU0_PE3_C_TXN<6>
  IO21  = P3E_CPU0_PE3_OCP_RXN<5>
  IO22  = GND
  IO23  = P3E_CPU0_PE3_OCP_RXP<5>
  IO24  = GND
  IO25  = GND
  IO26  = P3E_OCP_CPU0_PE3_C_TXP<5>
  IO27  = GND
  IO28  = P3E_OCP_CPU0_PE3_C_TXN<5>
  IO29  = P3E_CPU0_PE3_OCP_RXN<4>
  IO30  = GND
  IO31  = P3E_CPU0_PE3_OCP_RXP<4>
  IO32  = GND
  IO33  = GND
  IO34  = P3E_OCP_CPU0_PE3_C_TXP<4>
  IO35  = GND
  IO36  = P3E_OCP_CPU0_PE3_C_TXN<4>
  IO37  = P3E_CPU0_PE3_OCP_RXP<3>
  IO38  = GND
  IO39  = P3E_CPU0_PE3_OCP_RXN<3>
  IO40  = GND
  IO41  = GND
  IO42  = P3E_OCP_CPU0_PE3_C_TXP<3>
  IO43  = GND
  IO44  = P3E_OCP_CPU0_PE3_C_TXN<3>
  IO45  = P3E_CPU0_PE3_OCP_RXP<2>
  IO46  = GND
  IO47  = P3E_CPU0_PE3_OCP_RXN<2>
  IO48  = GND
  IO49  = GND
  IO50  = P3E_OCP_CPU0_PE3_C_TXP<2>
  IO51  = GND
  IO52  = P3E_OCP_CPU0_PE3_C_TXN<2>
  IO53  = P3E_CPU0_PE3_OCP_RXP<1>
  IO54  = GND
  IO55  = P3E_CPU0_PE3_OCP_RXN<1>
  IO56  = GND
  IO57  = GND
  IO58  = P3E_OCP_CPU0_PE3_C_TXP<1>
  IO59  = GND
  IO60  = P3E_OCP_CPU0_PE3_C_TXN<1>
  IO61  = P3E_CPU0_PE3_OCP_RXP<0>
  IO62  = GND
  IO63  = P3E_CPU0_PE3_OCP_RXN<0>
  IO64  = GND
  IO65  = GND
  IO66  = P3E_OCP_CPU0_PE3_C_TXP<0>
  IO67  = GND
  IO68  = P3E_OCP_CPU0_PE3_C_TXN<0>
  IO69  = CLK_100M_MEZZ3_DP
  IO70  = GND
  IO71  = CLK_100M_MEZZ3_DN
  IO72  = GND
  IO73  = GND
  IO74  = CLK_100M_MEZZ4_DP
  IO75  = RST_PCIE_CPU_DEV1_R_N
  IO76  = CLK_100M_MEZZ4_DN
  IO77  = RST_PCIE_CPU_DEV2_R_N
  IO78  = GND
  IO79  = RST_PCIE_CPU_DEV3_R_N
  IO80  = FM_OCP_MEZZB_PRES_N

(kicad_pcb
	(version 20260206)
	(generator "pcbnew")
	(generator_version "10.0")
	(general
		(thickness 1.6)
		(legacy_teardrops no)
	)
	(paper "A4")
	(title_block
		(title "Wiwynn_Tioga_Pass_MB.brd")
		(comment 1 "Tioga Pass / footprint 1403 of 4770 (J8E3), pads 1-47 of 82")
	)
	(layers
		(0 "F.Cu" signal "TOP")
		(4 "In1.Cu" signal "L2GND")
		(6 "In2.Cu" signal "L3")
		(8 "In3.Cu" signal "L4GND")
		(10 "In4.Cu" signal "L5")
		(12 "In5.Cu" signal "L6GND")
		(14 "In6.Cu" signal "L7VCC")
		(16 "In7.Cu" signal "L8VCC")
		(18 "In8.Cu" signal "L9GND")
		(20 "In9.Cu" signal "L10")
		(22 "In10.Cu" signal "L11GND")
		(24 "In11.Cu" signal "L12")
		(26 "In12.Cu" signal "L13GND")
		(2 "B.Cu" signal "BOTTOM")
		(9 "F.Adhes" user "F.Adhesive")
		(11 "B.Adhes" user "B.Adhesive")
		(13 "F.Paste" user "Package Geometry/Pastemask Top")
		(15 "B.Paste" user "Package Geometry/Pastemask Bottom")
		(5 "F.SilkS" user "Ref Des/Silkscreen Top")
		(7 "B.SilkS" user "Ref Des/Silkscreen Bottom")
		(1 "F.Mask" user "Board Geometry/Soldermask Top")
		(3 "B.Mask" user "Board Geometry/Soldermask Bottom")
		(17 "Dwgs.User" user "User.Drawings")
		(19 "Cmts.User" user "User.Comments")
		(21 "Eco1.User" user "User.Eco1")
		(23 "Eco2.User" user "User.Eco2")
		(25 "Edge.Cuts" user "Board Geometry/Outline")
		(27 "Margin" user)
		(31 "F.CrtYd" user "Package Geometry/Place Bound Top")
		(29 "B.CrtYd" user "Package Geometry/Place Bound Bottom")
		(35 "F.Fab" user "Ref Des/Assembly Top")
		(33 "B.Fab" user "Ref Des/Assembly Bottom")
	)
	(footprint ""
		(layer "F.Cu")
		(at 437.34101 -47.481998 90)
		(property "Reference" "J8E3"
			(at 6.402832 -4.049014 0)
			(unlocked yes)
			(layer "F.SilkS")
			(effects
				(font
					(size 0.7874 0.5842)
					(thickness 0.1524)
				)
				(justify left)
			)
		)
		(property "Value" ""
			(at 0 0 90)
			(layer "F.Fab")
			(effects
				(font
					(size 1.27 1.27)
				)
			)
		)
		(duplicate_pad_numbers_are_jumpers no)
		(pad "" np_thru_hole circle
			(at 2.1971 -2.489962 90)
			(size 0.254 0.254)
			(drill 1.3716)
			(layers "*.Cu" "*.Mask")
			(clearance 0.8763)
			(thermal_gap 0.8763)
		)
		(pad "" np_thru_hole circle
			(at 2.1971 33.702244 90)
			(size 0.254 0.254)
			(drill 1.016)
			(layers "*.Cu" "*.Mask")
			(clearance 0.6985)
			(thermal_gap 0.6985)
		)
		(pad "1" smd rect
			(at 0 0 90)
			(size 2.0066 0.508)
			(layers "F.Cu" "F.Mask" "F.Paste")
			(net "FM_MEZZB_PRSNT1_N")
		)
		(pad "2" smd rect
			(at 4.393946 0 90)
			(size 2.0066 0.508)
			(layers "F.Cu" "F.Mask" "F.Paste")
			(net "P12V_STBY")
		)
		(pad "3" smd rect
			(at 0 0.8001 90)
			(size 2.0066 0.508)
			(layers "F.Cu" "F.Mask" "F.Paste")
			(net "GND")
		)
		(pad "4" smd rect
			(at 4.393946 0.8001 90)
			(size 2.0066 0.508)
			(layers "F.Cu" "F.Mask" "F.Paste")
			(net "P12V_STBY")
		)
		(pad "5" smd rect
			(at 0 1.599946 90)
			(size 2.0066 0.508)
			(layers "F.Cu" "F.Mask" "F.Paste")
			(net "P3E_CPU0_PE3_OCP_RXP<7>")
		)
		(pad "6" smd rect
			(at 4.393946 1.599946 90)
			(size 2.0066 0.508)
			(layers "F.Cu" "F.Mask" "F.Paste")
			(net "TP_RSVD_B1")
		)
		(pad "7" smd rect
			(at 0 2.400046 90)
			(size 2.0066 0.508)
			(layers "F.Cu" "F.Mask" "F.Paste")
			(net "P3E_CPU0_PE3_OCP_RXN<7>")
		)
		(pad "8" smd rect
			(at 4.393946 2.400046 90)
			(size 2.0066 0.508)
			(layers "F.Cu" "F.Mask" "F.Paste")
			(net "GND")
		)
		(pad "9" smd rect
			(at 0 3.199892 90)
			(size 2.0066 0.508)
			(layers "F.Cu" "F.Mask" "F.Paste")
			(net "GND")
		)
		(pad "10" smd rect
			(at 4.393946 3.199892 90)
			(size 2.0066 0.508)
			(layers "F.Cu" "F.Mask" "F.Paste")
			(net "P3E_OCP_CPU0_PE3_C_TXP<7>")
		)
		(pad "11" smd rect
			(at 0 3.999992 90)
			(size 2.0066 0.508)
			(layers "F.Cu" "F.Mask" "F.Paste")
			(net "GND")
		)
		(pad "12" smd rect
			(at 4.393946 3.999992 90)
			(size 2.0066 0.508)
			(layers "F.Cu" "F.Mask" "F.Paste")
			(net "P3E_OCP_CPU0_PE3_C_TXN<7>")
		)
		(pad "13" smd rect
			(at 0 4.800092 90)
			(size 2.0066 0.508)
			(layers "F.Cu" "F.Mask" "F.Paste")
			(net "P3E_CPU0_PE3_OCP_RXN<6>")
		)
		(pad "14" smd rect
			(at 4.393946 4.800092 90)
			(size 2.0066 0.508)
			(layers "F.Cu" "F.Mask" "F.Paste")
			(net "GND")
		)
		(pad "15" smd rect
			(at 0 5.599938 90)
			(size 2.0066 0.508)
			(layers "F.Cu" "F.Mask" "F.Paste")
			(net "P3E_CPU0_PE3_OCP_RXP<6>")
		)
		(pad "16" smd rect
			(at 4.393946 5.599938 90)
			(size 2.0066 0.508)
			(layers "F.Cu" "F.Mask" "F.Paste")
			(net "GND")
		)
		(pad "17" smd rect
			(at 0 6.400038 90)
			(size 2.0066 0.508)
			(layers "F.Cu" "F.Mask" "F.Paste")
			(net "GND")
		)
		(pad "18" smd rect
			(at 4.393946 6.400038 90)
			(size 2.0066 0.508)
			(layers "F.Cu" "F.Mask" "F.Paste")
			(net "P3E_OCP_CPU0_PE3_C_TXP<6>")
		)
		(pad "19" smd rect
			(at 0 7.199884 90)
			(size 2.0066 0.508)
			(layers "F.Cu" "F.Mask" "F.Paste")
			(net "GND")
		)
		(pad "20" smd rect
			(at 4.393946 7.199884 90)
			(size 2.0066 0.508)
			(layers "F.Cu" "F.Mask" "F.Paste")
			(net "P3E_OCP_CPU0_PE3_C_TXN<6>")
		)
		(pad "21" smd rect
			(at 0 7.999984 90)
			(size 2.0066 0.508)
			(layers "F.Cu" "F.Mask" "F.Paste")
			(net "P3E_CPU0_PE3_OCP_RXN<5>")
		)
		(pad "22" smd rect
			(at 4.393946 7.999984 90)
			(size 2.0066 0.508)
			(layers "F.Cu" "F.Mask" "F.Paste")
			(net "GND")
		)
		(pad "23" smd rect
			(at 0 8.800084 90)
			(size 2.0066 0.508)
			(layers "F.Cu" "F.Mask" "F.Paste")
			(net "P3E_CPU0_PE3_OCP_RXP<5>")
		)
		(pad "24" smd rect
			(at 4.393946 8.800084 90)
			(size 2.0066 0.508)
			(layers "F.Cu" "F.Mask" "F.Paste")
			(net "GND")
		)
		(pad "25" smd rect
			(at 0 9.59993 90)
			(size 2.0066 0.508)
			(layers "F.Cu" "F.Mask" "F.Paste")
			(net "GND")
		)
		(pad "26" smd rect
			(at 4.393946 9.59993 90)
			(size 2.0066 0.508)
			(layers "F.Cu" "F.Mask" "F.Paste")
			(net "P3E_OCP_CPU0_PE3_C_TXP<5>")
		)
		(pad "27" smd rect
			(at 0 10.40003 90)
			(size 2.0066 0.508)
			(layers "F.Cu" "F.Mask" "F.Paste")
			(net "GND")
		)
		(pad "28" smd rect
			(at 4.393946 10.40003 90)
			(size 2.0066 0.508)
			(layers "F.Cu" "F.Mask" "F.Paste")
			(net "P3E_OCP_CPU0_PE3_C_TXN<5>")
		)
		(pad "29" smd rect
			(at 0 11.199876 90)
			(size 2.0066 0.508)
			(layers "F.Cu" "F.Mask" "F.Paste")
			(net "P3E_CPU0_PE3_OCP_RXN<4>")
		)
		(pad "30" smd rect
			(at 4.393946 11.199876 90)
			(size 2.0066 0.508)
			(layers "F.Cu" "F.Mask" "F.Paste")
			(net "GND")
		)
		(pad "31" smd rect
			(at 0 11.999976 90)
			(size 2.0066 0.508)
			(layers "F.Cu" "F.Mask" "F.Paste")
			(net "P3E_CPU0_PE3_OCP_RXP<4>")
		)
		(pad "32" smd rect
			(at 4.393946 11.999976 90)
			(size 2.0066 0.508)
			(layers "F.Cu" "F.Mask" "F.Paste")
			(net "GND")
		)
		(pad "33" smd rect
			(at 0 12.800076 90)
			(size 2.0066 0.508)
			(layers "F.Cu" "F.Mask" "F.Paste")
			(net "GND")
		)
		(pad "34" smd rect
			(at 4.393946 12.800076 90)
			(size 2.0066 0.508)
			(layers "F.Cu" "F.Mask" "F.Paste")
			(net "P3E_OCP_CPU0_PE3_C_TXP<4>")
		)
		(pad "35" smd rect
			(at 0 13.599922 90)
			(size 2.0066 0.508)
			(layers "F.Cu" "F.Mask" "F.Paste")
			(net "GND")
		)
		(pad "36" smd rect
			(at 4.393946 13.599922 90)
			(size 2.0066 0.508)
			(layers "F.Cu" "F.Mask" "F.Paste")
			(net "P3E_OCP_CPU0_PE3_C_TXN<4>")
		)
		(pad "37" smd rect
			(at 0 14.400022 90)
			(size 2.0066 0.508)
			(layers "F.Cu" "F.Mask" "F.Paste")
			(net "P3E_CPU0_PE3_OCP_RXP<3>")
		)
		(pad "38" smd rect
			(at 4.393946 14.400022 90)
			(size 2.0066 0.508)
			(layers "F.Cu" "F.Mask" "F.Paste")
			(net "GND")
		)
		(pad "39" smd rect
			(at 0 15.200122 90)
			(size 2.0066 0.508)
			(layers "F.Cu" "F.Mask" "F.Paste")
			(net "P3E_CPU0_PE3_OCP_RXN<3>")
		)
		(pad "40" smd rect
			(at 4.393946 15.200122 90)
			(size 2.0066 0.508)
			(layers "F.Cu" "F.Mask" "F.Paste")
			(net "GND")
		)
		(pad "41" smd rect
			(at 0 15.999968 90)
			(size 2.0066 0.508)
			(layers "F.Cu" "F.Mask" "F.Paste")
			(net "GND")
		)
		(pad "42" smd rect
			(at 4.393946 15.999968 90)
			(size 2.0066 0.508)
			(layers "F.Cu" "F.Mask" "F.Paste")
			(net "P3E_OCP_CPU0_PE3_C_TXP<3>")
		)
		(pad "43" smd rect
			(at 0 16.800068 90)
			(size 2.0066 0.508)
			(layers "F.Cu" "F.Mask" "F.Paste")
			(net "GND")
		)
		(pad "44" smd rect
			(at 4.393946 16.800068 90)
			(size 2.0066 0.508)
			(layers "F.Cu" "F.Mask" "F.Paste")
			(net "P3E_OCP_CPU0_PE3_C_TXN<3>")
		)
		(pad "45" smd rect
			(at 0 17.599914 90)
			(size 2.0066 0.508)
			(layers "F.Cu" "F.Mask" "F.Paste")
			(net "P3E_CPU0_PE3_OCP_RXP<2>")
		)
	)
)
